# S9S_MB_2U (Grand Teton) — schematic netlist excerpt (pin names and nets, part order shuffled) for the footprints in the layout excerpt that follows; sources: Cadence DE-HDL packaged netlist, KiCad conversion of 03242023_DA0F0TMBIJ0_F0T_Motherboard_J_brd_V01_OCP.brd

PL106  Q_INDUCTOR  120NH/69A IND  pkg SMLF  page 288 : \1\ = IND_P1_CPL8 ; \2\ = GND
R3460  Q_RES  100K 1% EMPTY  pkg 0402LF  page 150 : A = GPU_NVS_PWR_BRAKE_N ; B = GND
R4628  Q_RES  0 5% CHIP  pkg 0402LF  page 248 : A = JTAG_BMC_TMS ; B = JTAG_BMC_TMS_R

(kicad_pcb
	(version 20260206)
	(generator "pcbnew")
	(generator_version "10.0")
	(general
		(thickness 1.6)
		(legacy_teardrops no)
	)
	(paper "A4")
	(title_block
		(title "03242023_DA0F0TMBIJ0_F0T_Motherboard_J_brd_V01_OCP.brd")
		(comment 1 "Grand Teton / footprints 3645-3647 of 6105")
	)
	(layers
		(0 "F.Cu" signal "TOP")
		(4 "In1.Cu" signal "GND")
		(6 "In2.Cu" signal "IN1")
		(8 "In3.Cu" signal "GND1")
		(10 "In4.Cu" signal "IN2")
		(12 "In5.Cu" signal "GND2")
		(14 "In6.Cu" signal "IN3")
		(16 "In7.Cu" signal "GND3")
		(18 "In8.Cu" signal "VCC")
		(20 "In9.Cu" signal "VCC1")
		(22 "In10.Cu" signal "GND4")
		(24 "In11.Cu" signal "IN4")
		(26 "In12.Cu" signal "GND5")
		(28 "In13.Cu" signal "IN5")
		(30 "In14.Cu" signal "GND6")
		(32 "In15.Cu" signal "IN6")
		(34 "In16.Cu" signal "GND7")
		(2 "B.Cu" signal "BOTTOM")
		(9 "F.Adhes" user "F.Adhesive")
		(11 "B.Adhes" user "B.Adhesive")
		(13 "F.Paste" user "Package Geometry/Pastemask Top")
		(15 "B.Paste" user "Package Geometry/Pastemask Bottom")
		(5 "F.SilkS" user "Ref Des/Silkscreen Top")
		(7 "B.SilkS" user "Ref Des/Silkscreen Bottom")
		(1 "F.Mask" user "Board Geometry/Soldermask Top")
		(3 "B.Mask" user "Board Geometry/Soldermask Bottom")
		(17 "Dwgs.User" user "User.Drawings")
		(19 "Cmts.User" user "User.Comments")
		(21 "Eco1.User" user "User.Eco1")
		(23 "Eco2.User" user "User.Eco2")
		(25 "Edge.Cuts" user "Board Geometry/Outline")
		(27 "Margin" user)
		(31 "F.CrtYd" user "Package Geometry/Place Bound Top")
		(29 "B.CrtYd" user "Package Geometry/Place Bound Bottom")
		(35 "F.Fab" user "Ref Des/Assembly Top")
		(33 "B.Fab" user "Ref Des/Assembly Bottom")
	)
	(footprint ""
		(layer "F.Cu")
		(at 143.764 -25.110948 180)
		(property "Reference" "R4628"
			(at 0 0 180)
			(layer "F.SilkS")
			(hide yes)
			(effects
				(font
					(size 1.27 1.27)
				)
			)
		)
		(property "Value" ""
			(at 0 0 180)
			(layer "F.Fab")
			(effects
				(font
					(size 1.27 1.27)
				)
			)
		)
		(duplicate_pad_numbers_are_jumpers no)
		(fp_line
			(start 0.7874 0.4064)
			(end -0.7874 0.4064)
			(stroke
				(width 0.1524)
				(type default)
			)
			(layer "F.SilkS")
		)
		(fp_line
			(start 0.7874 -0.4064)
			(end 0.7874 0.4064)
			(stroke
				(width 0.1524)
				(type default)
			)
			(layer "F.SilkS")
		)
		(fp_line
			(start -0.7874 0.4064)
			(end -0.7874 -0.4064)
			(stroke
				(width 0.1524)
				(type default)
			)
			(layer "F.SilkS")
		)
		(fp_line
			(start -0.7874 -0.4064)
			(end 0.7874 -0.4064)
			(stroke
				(width 0.1524)
				(type default)
			)
			(layer "F.SilkS")
		)
		(fp_line
			(start 0.67945 0.3048)
			(end 0.120396 0.3048)
			(stroke
				(width 0.1)
				(type default)
			)
			(layer "F.Fab")
		)
		(fp_line
			(start 0.67945 -0.3048)
			(end 0.67945 0.3048)
			(stroke
				(width 0.1)
				(type default)
			)
			(layer "F.Fab")
		)
		(fp_line
			(start 0.12065 -0.2794)
			(end 0.12065 -0.3048)
			(stroke
				(width 0.1)
				(type default)
			)
			(layer "F.Fab")
		)
		(fp_line
			(start 0.12065 -0.3048)
			(end 0.67945 -0.3048)
			(stroke
				(width 0.1)
				(type default)
			)
			(layer "F.Fab")
		)
		(fp_line
			(start 0.120396 0.3048)
			(end 0.120396 0.2794)
			(stroke
				(width 0.1)
				(type default)
			)
			(layer "F.Fab")
		)
		(fp_line
			(start 0.120396 0.2794)
			(end -0.12065 0.2794)
			(stroke
				(width 0.1)
				(type default)
			)
			(layer "F.Fab")
		)
		(fp_line
			(start -0.12065 0.3048)
			(end -0.67945 0.3048)
			(stroke
				(width 0.1)
				(type default)
			)
			(layer "F.Fab")
		)
		(fp_line
			(start -0.12065 0.2794)
			(end -0.12065 0.3048)
			(stroke
				(width 0.1)
				(type default)
			)
			(layer "F.Fab")
		)
		(fp_line
			(start -0.12065 -0.2794)
			(end 0.12065 -0.2794)
			(stroke
				(width 0.1)
				(type default)
			)
			(layer "F.Fab")
		)
		(fp_line
			(start -0.12065 -0.305054)
			(end -0.12065 -0.2794)
			(stroke
				(width 0.1)
				(type default)
			)
			(layer "F.Fab")
		)
		(fp_line
			(start -0.67945 0.3048)
			(end -0.67945 -0.305054)
			(stroke
				(width 0.1)
				(type default)
			)
			(layer "F.Fab")
		)
		(fp_line
			(start -0.67945 -0.305054)
			(end -0.12065 -0.305054)
			(stroke
				(width 0.1)
				(type default)
			)
			(layer "F.Fab")
		)
		(pad "1" smd circle
			(at -0.40005 0 180)
			(size 0 0)
			(layers "F.Cu" "F.Mask" "F.Paste")
			(net "JTAG_BMC_TMS")
		)
		(pad "2" smd circle
			(at 0.40005 0 180)
			(size 0 0)
			(layers "F.Cu" "F.Mask" "F.Paste")
			(net "JTAG_BMC_TMS_R")
		)
	)
	(footprint ""
		(layer "F.Cu")
		(at 145.46326 -338.393532 90)
		(property "Reference" "PL106"
			(at -4.419854 0.37338 0)
			(unlocked yes)
			(layer "F.SilkS")
			(effects
				(font
					(size 0.7874 0.5842)
					(thickness 0.1524)
				)
				(justify left)
			)
		)
		(property "Value" ""
			(at 0 0 90)
			(layer "F.Fab")
			(effects
				(font
					(size 1.27 1.27)
				)
			)
		)
		(duplicate_pad_numbers_are_jumpers no)
		(fp_line
			(start 3.24993 -3.24993)
			(end 3.24993 -2.2352)
			(stroke
				(width 0.1524)
				(type default)
			)
			(layer "F.SilkS")
		)
		(fp_line
			(start -3.24993 -3.24993)
			(end 3.24993 -3.24993)
			(stroke
				(width 0.1524)
				(type default)
			)
			(layer "F.SilkS")
		)
		(fp_line
			(start -3.24993 -2.2352)
			(end -3.24993 -3.24993)
			(stroke
				(width 0.1524)
				(type default)
			)
			(layer "F.SilkS")
		)
		(fp_line
			(start 3.24993 2.2352)
			(end 3.24993 3.24993)
			(stroke
				(width 0.1524)
				(type default)
			)
			(layer "F.SilkS")
		)
		(fp_line
			(start 3.24993 3.24993)
			(end -3.24993 3.24993)
			(stroke
				(width 0.1524)
				(type default)
			)
			(layer "F.SilkS")
		)
		(fp_line
			(start -3.24993 3.24993)
			(end -3.24993 2.2352)
			(stroke
				(width 0.1524)
				(type default)
			)
			(layer "F.SilkS")
		)
		(fp_line
			(start 3.24993 -3.24993)
			(end 3.24993 3.24993)
			(stroke
				(width 0.1)
				(type default)
			)
			(layer "F.Fab")
		)
		(fp_line
			(start -3.24993 -3.24993)
			(end 3.24993 -3.24993)
			(stroke
				(width 0.1)
				(type default)
			)
			(layer "F.Fab")
		)
		(fp_line
			(start 3.24993 3.24993)
			(end -3.24993 3.24993)
			(stroke
				(width 0.1)
				(type default)
			)
			(layer "F.Fab")
		)
		(fp_line
			(start -3.24993 3.24993)
			(end -3.24993 -3.24993)
			(stroke
				(width 0.1)
				(type default)
			)
			(layer "F.Fab")
		)
		(pad "1" smd rect
			(at -2.29997 0 90)
			(size 2.0066 4.2164)
			(layers "F.Cu" "F.Mask" "F.Paste")
			(net "IND_P1_CPL8")
		)
		(pad "2" smd rect
			(at 2.29997 0 90)
			(size 2.0066 4.2164)
			(layers "F.Cu" "F.Mask" "F.Paste")
			(net "GND")
		)
	)
	(footprint ""
		(layer "F.Cu")
		(at 109.580934 -392.12774)
		(property "Reference" "R3460"
			(at 0 0 0)
			(layer "F.SilkS")
			(hide yes)
			(effects
				(font
					(size 1.27 1.27)
				)
			)
		)
		(property "Value" ""
			(at 0 0 0)
			(layer "F.Fab")
			(effects
				(font
					(size 1.27 1.27)
				)
			)
		)
		(duplicate_pad_numbers_are_jumpers no)
		(fp_line
			(start -0.7874 -0.4064)
			(end 0.7874 -0.4064)
			(stroke
				(width 0.1524)
				(type default)
			)
			(layer "F.SilkS")
		)
		(fp_line
			(start -0.7874 0.4064)
			(end -0.7874 -0.4064)
			(stroke
				(width 0.1524)
				(type default)
			)
			(layer "F.SilkS")
		)
		(fp_line
			(start 0.7874 -0.4064)
			(end 0.7874 0.4064)
			(stroke
				(width 0.1524)
				(type default)
			)
			(layer "F.SilkS")
		)
		(fp_line
			(start 0.7874 0.4064)
			(end -0.7874 0.4064)
			(stroke
				(width 0.1524)
				(type default)
			)
			(layer "F.SilkS")
		)
		(fp_line
			(start -0.67945 -0.305054)
			(end -0.12065 -0.305054)
			(stroke
				(width 0.1)
				(type default)
			)
			(layer "F.Fab")
		)
		(fp_line
			(start -0.67945 0.3048)
			(end -0.67945 -0.305054)
			(stroke
				(width 0.1)
				(type default)
			)
			(layer "F.Fab")
		)
		(fp_line
			(start -0.12065 -0.305054)
			(end -0.12065 -0.2794)
			(stroke
				(width 0.1)
				(type default)
			)
			(layer "F.Fab")
		)
		(fp_line
			(start -0.12065 -0.2794)
			(end 0.12065 -0.2794)
			(stroke
				(width 0.1)
				(type default)
			)
			(layer "F.Fab")
		)
		(fp_line
			(start -0.12065 0.2794)
			(end -0.12065 0.3048)
			(stroke
				(width 0.1)
				(type default)
			)
			(layer "F.Fab")
		)
		(fp_line
			(start -0.12065 0.3048)
			(end -0.67945 0.3048)
			(stroke
				(width 0.1)
				(type default)
			)
			(layer "F.Fab")
		)
		(fp_line
			(start 0.120396 0.2794)
			(end -0.12065 0.2794)
			(stroke
				(width 0.1)
				(type default)
			)
			(layer "F.Fab")
		)
		(fp_line
			(start 0.120396 0.3048)
			(end 0.120396 0.2794)
			(stroke
				(width 0.1)
				(type default)
			)
			(layer "F.Fab")
		)
		(fp_line
			(start 0.12065 -0.3048)
			(end 0.67945 -0.3048)
			(stroke
				(width 0.1)
				(type default)
			)
			(layer "F.Fab")
		)
		(fp_line
			(start 0.12065 -0.2794)
			(end 0.12065 -0.3048)
			(stroke
				(width 0.1)
				(type default)
			)
			(layer "F.Fab")
		)
		(fp_line
			(start 0.67945 -0.3048)
			(end 0.67945 0.3048)
			(stroke
				(width 0.1)
				(type default)
			)
			(layer "F.Fab")
		)
		(fp_line
			(start 0.67945 0.3048)
			(end 0.120396 0.3048)
			(stroke
				(width 0.1)
				(type default)
			)
			(layer "F.Fab")
		)
		(pad "1" smd circle
			(at -0.40005 0)
			(size 0 0)
			(layers "F.Cu" "F.Mask" "F.Paste")
			(net "GPU_NVS_PWR_BRAKE_N")
		)
		(pad "2" smd circle
			(at 0.40005 0)
			(size 0 0)
			(layers "F.Cu" "F.Mask" "F.Paste")
			(net "GND")
		)
	)
)
